(kicad_pcb
	(version 20260206)
	(generator "pcbnew")
	(generator_version "10.0")
	(general
		(thickness 1.6)
		(legacy_teardrops no)
	)
	(paper "A4")
	(title_block
		(title "04192023_DAF0TMB3IC0_F0TG_MB_C_brd_V02_OCP.brd")
		(comment 1 "Grand Teton / footprints 1702-1708 of 8354")
	)
	(layers
		(0 "F.Cu" signal "TOP")
		(4 "In1.Cu" signal "GND")
		(6 "In2.Cu" signal "IN1")
		(8 "In3.Cu" signal "GND1")
		(10 "In4.Cu" signal "IN2")
		(12 "In5.Cu" signal "GND2")
		(14 "In6.Cu" signal "IN3")
		(16 "In7.Cu" signal "GND3")
		(18 "In8.Cu" signal "VCC")
		(20 "In9.Cu" signal "VCC1")
		(22 "In10.Cu" signal "GND4")
		(24 "In11.Cu" signal "IN4")
		(26 "In12.Cu" signal "GND5")
		(28 "In13.Cu" signal "IN5")
		(30 "In14.Cu" signal "GND6")
		(32 "In15.Cu" signal "IN6")
		(34 "In16.Cu" signal "GND7")
		(2 "B.Cu" signal "BOTTOM")
		(9 "F.Adhes" user "F.Adhesive")
		(11 "B.Adhes" user "B.Adhesive")
		(13 "F.Paste" user "Package Geometry/Pastemask Top")
		(15 "B.Paste" user "Package Geometry/Pastemask Bottom")
		(5 "F.SilkS" user "Ref Des/Silkscreen Top")
		(7 "B.SilkS" user "Ref Des/Silkscreen Bottom")
		(1 "F.Mask" user "Board Geometry/Soldermask Top")
		(3 "B.Mask" user "Board Geometry/Soldermask Bottom")
		(17 "Dwgs.User" user "User.Drawings")
		(19 "Cmts.User" user "User.Comments")
		(21 "Eco1.User" user "User.Eco1")
		(23 "Eco2.User" user "User.Eco2")
		(25 "Edge.Cuts" user "Board Geometry/Outline")
		(27 "Margin" user)
		(31 "F.CrtYd" user "Package Geometry/Place Bound Top")
		(29 "B.CrtYd" user "Package Geometry/Place Bound Bottom")
		(35 "F.Fab" user "Ref Des/Assembly Top")
		(33 "B.Fab" user "Ref Des/Assembly Bottom")
	)
	(footprint ""
		(layer "F.Cu")
		(at 144.690592 -104.974898)
		(property "Reference" "Q95"
			(at -3.91668 -1.633728 0)
			(unlocked yes)
			(layer "F.SilkS")
			(effects
				(font
					(size 0.7874 0.5842)
					(thickness 0.1524)
				)
				(justify left)
			)
		)
		(property "Value" ""
			(at 0 0 0)
			(layer "F.Fab")
			(effects
				(font
					(size 1.27 1.27)
				)
			)
		)
		(duplicate_pad_numbers_are_jumpers no)
		(fp_line
			(start -1.332738 -1.100074)
			(end -0.4826 -1.100074)
			(stroke
				(width 0.1524)
				(type default)
			)
			(layer "F.SilkS")
		)
		(fp_line
			(start -1.332738 1.100074)
			(end -1.332738 -1.100074)
			(stroke
				(width 0.1524)
				(type default)
			)
			(layer "F.SilkS")
		)
		(fp_line
			(start -0.4826 -1.100074)
			(end 0 -0.541274)
			(stroke
				(width 0.1524)
				(type default)
			)
			(layer "F.SilkS")
		)
		(fp_line
			(start 0 -0.541274)
			(end 0.4826 -1.100074)
			(stroke
				(width 0.1524)
				(type default)
			)
			(layer "F.SilkS")
		)
		(fp_line
			(start 0.4826 -1.100074)
			(end 1.332738 -1.100074)
			(stroke
				(width 0.1524)
				(type default)
			)
			(layer "F.SilkS")
		)
		(fp_line
			(start 1.332738 -1.100074)
			(end 1.332738 1.100074)
			(stroke
				(width 0.1524)
				(type default)
			)
			(layer "F.SilkS")
		)
		(fp_line
			(start 1.332738 1.100074)
			(end -1.332738 1.100074)
			(stroke
				(width 0.1524)
				(type default)
			)
			(layer "F.SilkS")
		)
		(fp_poly
			(pts
				(xy -1.533144 -0.649986) (xy -2.1082 -0.362458) (xy -2.1082 -0.937514)
			)
			(stroke
				(width 0)
				(type default)
			)
			(fill yes)
			(layer "F.SilkS")
		)
		(fp_line
			(start -0.674878 -1.100074)
			(end 0.674878 -1.100074)
			(stroke
				(width 0.1)
				(type default)
			)
			(layer "F.Fab")
		)
		(fp_line
			(start -0.674878 1.100074)
			(end -0.674878 -1.100074)
			(stroke
				(width 0.1)
				(type default)
			)
			(layer "F.Fab")
		)
		(fp_line
			(start 0.674878 -1.100074)
			(end 0.674878 1.100074)
			(stroke
				(width 0.1)
				(type default)
			)
			(layer "F.Fab")
		)
		(fp_line
			(start 0.674878 1.100074)
			(end -0.674878 1.100074)
			(stroke
				(width 0.1)
				(type default)
			)
			(layer "F.Fab")
		)
		(fp_poly
			(pts
				(xy -2.2352 -0.298958) (xy -2.2352 -1.001014) (xy -1.533144 -0.649986)
			)
			(stroke
				(width 0)
				(type default)
			)
			(fill yes)
			(layer "F.Fab")
		)
		(pad "1" smd rect
			(at -0.94996 -0.649986 90)
			(size 0.4318 0.508)
			(layers "F.Cu" "F.Mask" "F.Paste")
			(net "GND")
		)
		(pad "2" smd rect
			(at -0.94996 0 90)
			(size 0.4318 0.508)
			(layers "F.Cu" "F.Mask" "F.Paste")
			(net "HDD_ACTIVITY_BUF")
		)
		(pad "3" smd rect
			(at -0.94996 0.649986 90)
			(size 0.4318 0.508)
			(layers "F.Cu" "F.Mask" "F.Paste")
			(net "NC_Q95_D2")
		)
		(pad "4" smd rect
			(at 0.94996 0.649986 90)
			(size 0.4318 0.508)
			(layers "F.Cu" "F.Mask" "F.Paste")
			(net "NC_Q95_S2")
		)
		(pad "5" smd rect
			(at 0.94996 0 90)
			(size 0.4318 0.508)
			(layers "F.Cu" "F.Mask" "F.Paste")
			(net "NC_Q95_G2")
		)
		(pad "6" smd rect
			(at 0.94996 -0.649986 90)
			(size 0.4318 0.508)
			(layers "F.Cu" "F.Mask" "F.Paste")
			(net "HDD_ACTIVITY_BUF_N")
		)
	)
	(footprint ""
		(layer "F.Cu")
		(at 64.888364 -164.276786 -90)
		(property "Reference" "PR424"
			(at 0 0 270)
			(layer "F.SilkS")
			(hide yes)
			(effects
				(font
					(size 1.27 1.27)
				)
			)
		)
		(property "Value" ""
			(at 0 0 270)
			(layer "F.Fab")
			(effects
				(font
					(size 1.27 1.27)
				)
			)
		)
		(duplicate_pad_numbers_are_jumpers no)
		(fp_line
			(start -0.7874 0.4064)
			(end -0.7874 -0.4064)
			(stroke
				(width 0.1524)
				(type default)
			)
			(layer "F.SilkS")
		)
		(fp_line
			(start 0.7874 0.4064)
			(end -0.7874 0.4064)
			(stroke
				(width 0.1524)
				(type default)
			)
			(layer "F.SilkS")
		)
		(fp_line
			(start -0.7874 -0.4064)
			(end 0.7874 -0.4064)
			(stroke
				(width 0.1524)
				(type default)
			)
			(layer "F.SilkS")
		)
		(fp_line
			(start 0.7874 -0.4064)
			(end 0.7874 0.4064)
			(stroke
				(width 0.1524)
				(type default)
			)
			(layer "F.SilkS")
		)
		(fp_line
			(start -0.67945 0.3048)
			(end -0.67945 -0.305054)
			(stroke
				(width 0.1)
				(type default)
			)
			(layer "F.Fab")
		)
		(fp_line
			(start -0.12065 0.3048)
			(end -0.67945 0.3048)
			(stroke
				(width 0.1)
				(type default)
			)
			(layer "F.Fab")
		)
		(fp_line
			(start 0.120396 0.3048)
			(end 0.120396 0.2794)
			(stroke
				(width 0.1)
				(type default)
			)
			(layer "F.Fab")
		)
		(fp_line
			(start 0.67945 0.3048)
			(end 0.120396 0.3048)
			(stroke
				(width 0.1)
				(type default)
			)
			(layer "F.Fab")
		)
		(fp_line
			(start -0.12065 0.2794)
			(end -0.12065 0.3048)
			(stroke
				(width 0.1)
				(type default)
			)
			(layer "F.Fab")
		)
		(fp_line
			(start 0.120396 0.2794)
			(end -0.12065 0.2794)
			(stroke
				(width 0.1)
				(type default)
			)
			(layer "F.Fab")
		)
		(fp_line
			(start -0.12065 -0.2794)
			(end 0.12065 -0.2794)
			(stroke
				(width 0.1)
				(type default)
			)
			(layer "F.Fab")
		)
		(fp_line
			(start 0.12065 -0.2794)
			(end 0.12065 -0.3048)
			(stroke
				(width 0.1)
				(type default)
			)
			(layer "F.Fab")
		)
		(fp_line
			(start 0.12065 -0.3048)
			(end 0.67945 -0.3048)
			(stroke
				(width 0.1)
				(type default)
			)
			(layer "F.Fab")
		)
		(fp_line
			(start 0.67945 -0.3048)
			(end 0.67945 0.3048)
			(stroke
				(width 0.1)
				(type default)
			)
			(layer "F.Fab")
		)
		(fp_line
			(start -0.67945 -0.305054)
			(end -0.12065 -0.305054)
			(stroke
				(width 0.1)
				(type default)
			)
			(layer "F.Fab")
		)
		(fp_line
			(start -0.12065 -0.305054)
			(end -0.12065 -0.2794)
			(stroke
				(width 0.1)
				(type default)
			)
			(layer "F.Fab")
		)
		(pad "1" smd circle
			(at -0.40005 0 270)
			(size 0 0)
			(layers "F.Cu" "F.Mask" "F.Paste")
			(net "SW_PVDDCR_CPU0_P1_BOOT6")
		)
		(pad "2" smd circle
			(at 0.40005 0 270)
			(size 0 0)
			(layers "F.Cu" "F.Mask" "F.Paste")
			(net "SW_PVDDCR_CPU0_P1_BOOT6_RC")
		)
	)
	(footprint ""
		(layer "F.Cu")
		(at 20.00504 -332.004924 180)
		(property "Reference" "TP15"
			(at 6.88848 1.024382 0)
			(unlocked yes)
			(layer "F.SilkS")
			(effects
				(font
					(size 0.7874 0.5842)
					(thickness 0.1524)
				)
				(justify left)
			)
		)
		(property "Value" ""
			(at 0 0 180)
			(layer "F.Fab")
			(effects
				(font
					(size 1.27 1.27)
				)
			)
		)
		(duplicate_pad_numbers_are_jumpers no)
		(pad "1" smd circle
			(at 0 0 180)
			(size 0.762 0.762)
			(layers "F.Cu" "F.Mask" "F.Paste")
			(net "VSENSE_PVDDIO_P1_DP")
		)
	)
	(footprint ""
		(layer "F.Cu")
		(at 304.419 -358.14)
		(property "Reference" "PR8008"
			(at 0 0 0)
			(layer "F.SilkS")
			(hide yes)
			(effects
				(font
					(size 1.27 1.27)
				)
			)
		)
		(property "Value" ""
			(at 0 0 0)
			(layer "F.Fab")
			(effects
				(font
					(size 1.27 1.27)
				)
			)
		)
		(duplicate_pad_numbers_are_jumpers no)
		(fp_line
			(start -0.7874 -0.4064)
			(end 0.7874 -0.4064)
			(stroke
				(width 0.1524)
				(type default)
			)
			(layer "F.SilkS")
		)
		(fp_line
			(start -0.7874 0.4064)
			(end -0.7874 -0.4064)
			(stroke
				(width 0.1524)
				(type default)
			)
			(layer "F.SilkS")
		)
		(fp_line
			(start 0.7874 -0.4064)
			(end 0.7874 0.4064)
			(stroke
				(width 0.1524)
				(type default)
			)
			(layer "F.SilkS")
		)
		(fp_line
			(start 0.7874 0.4064)
			(end -0.7874 0.4064)
			(stroke
				(width 0.1524)
				(type default)
			)
			(layer "F.SilkS")
		)
		(fp_line
			(start -0.67945 -0.305054)
			(end -0.12065 -0.305054)
			(stroke
				(width 0.1)
				(type default)
			)
			(layer "F.Fab")
		)
		(fp_line
			(start -0.67945 0.3048)
			(end -0.67945 -0.305054)
			(stroke
				(width 0.1)
				(type default)
			)
			(layer "F.Fab")
		)
		(fp_line
			(start -0.12065 -0.305054)
			(end -0.12065 -0.2794)
			(stroke
				(width 0.1)
				(type default)
			)
			(layer "F.Fab")
		)
		(fp_line
			(start -0.12065 -0.2794)
			(end 0.12065 -0.2794)
			(stroke
				(width 0.1)
				(type default)
			)
			(layer "F.Fab")
		)
		(fp_line
			(start -0.12065 0.2794)
			(end -0.12065 0.3048)
			(stroke
				(width 0.1)
				(type default)
			)
			(layer "F.Fab")
		)
		(fp_line
			(start -0.12065 0.3048)
			(end -0.67945 0.3048)
			(stroke
				(width 0.1)
				(type default)
			)
			(layer "F.Fab")
		)
		(fp_line
			(start 0.120396 0.2794)
			(end -0.12065 0.2794)
			(stroke
				(width 0.1)
				(type default)
			)
			(layer "F.Fab")
		)
		(fp_line
			(start 0.120396 0.3048)
			(end 0.120396 0.2794)
			(stroke
				(width 0.1)
				(type default)
			)
			(layer "F.Fab")
		)
		(fp_line
			(start 0.12065 -0.3048)
			(end 0.67945 -0.3048)
			(stroke
				(width 0.1)
				(type default)
			)
			(layer "F.Fab")
		)
		(fp_line
			(start 0.12065 -0.2794)
			(end 0.12065 -0.3048)
			(stroke
				(width 0.1)
				(type default)
			)
			(layer "F.Fab")
		)
		(fp_line
			(start 0.67945 -0.3048)
			(end 0.67945 0.3048)
			(stroke
				(width 0.1)
				(type default)
			)
			(layer "F.Fab")
		)
		(fp_line
			(start 0.67945 0.3048)
			(end 0.120396 0.3048)
			(stroke
				(width 0.1)
				(type default)
			)
			(layer "F.Fab")
		)
		(pad "1" smd circle
			(at -0.40005 0)
			(size 0 0)
			(layers "F.Cu" "F.Mask" "F.Paste")
			(net "SVID_PVDDCR_CPU1_P0_SVD_R")
		)
		(pad "2" smd circle
			(at 0.40005 0)
			(size 0 0)
			(layers "F.Cu" "F.Mask" "F.Paste")
			(net "SVID_PVDDCR_CPU1_P0_SVD_R1")
		)
	)
	(footprint ""
		(layer "F.Cu")
		(at 280.019506 -349.381572 90)
		(property "Reference" "PC172"
			(at 0 0 90)
			(layer "F.SilkS")
			(hide yes)
			(effects
				(font
					(size 1.27 1.27)
				)
			)
		)
		(property "Value" ""
			(at 0 0 90)
			(layer "F.Fab")
			(effects
				(font
					(size 1.27 1.27)
				)
			)
		)
		(duplicate_pad_numbers_are_jumpers no)
		(fp_line
			(start 0.7874 -0.4064)
			(end 0.7874 0.4064)
			(stroke
				(width 0.1524)
				(type default)
			)
			(layer "F.SilkS")
		)
		(fp_line
			(start -0.7874 -0.4064)
			(end 0.7874 -0.4064)
			(stroke
				(width 0.1524)
				(type default)
			)
			(layer "F.SilkS")
		)
		(fp_line
			(start 0.7874 0.4064)
			(end 0.452628 0.4064)
			(stroke
				(width 0.1524)
				(type default)
			)
			(layer "F.SilkS")
		)
		(fp_line
			(start -0.258572 0.4064)
			(end -0.7874 0.4064)
			(stroke
				(width 0.1524)
				(type default)
			)
			(layer "F.SilkS")
		)
		(fp_line
			(start -0.7874 0.4064)
			(end -0.7874 -0.4064)
			(stroke
				(width 0.1524)
				(type default)
			)
			(layer "F.SilkS")
		)
		(fp_line
			(start -0.12065 -0.305054)
			(end -0.12065 -0.2794)
			(stroke
				(width 0.1)
				(type default)
			)
			(layer "F.Fab")
		)
		(fp_line
			(start -0.67945 -0.305054)
			(end -0.12065 -0.305054)
			(stroke
				(width 0.1)
				(type default)
			)
			(layer "F.Fab")
		)
		(fp_line
			(start 0.67945 -0.3048)
			(end 0.67945 0.3048)
			(stroke
				(width 0.1)
				(type default)
			)
			(layer "F.Fab")
		)
		(fp_line
			(start 0.12065 -0.3048)
			(end 0.67945 -0.3048)
			(stroke
				(width 0.1)
				(type default)
			)
			(layer "F.Fab")
		)
		(fp_line
			(start 0.12065 -0.2794)
			(end 0.12065 -0.3048)
			(stroke
				(width 0.1)
				(type default)
			)
			(layer "F.Fab")
		)
		(fp_line
			(start -0.12065 -0.2794)
			(end 0.12065 -0.2794)
			(stroke
				(width 0.1)
				(type default)
			)
			(layer "F.Fab")
		)
		(fp_line
			(start 0.120396 0.2794)
			(end -0.12065 0.2794)
			(stroke
				(width 0.1)
				(type default)
			)
			(layer "F.Fab")
		)
		(fp_line
			(start -0.12065 0.2794)
			(end -0.12065 0.3048)
			(stroke
				(width 0.1)
				(type default)
			)
			(layer "F.Fab")
		)
		(fp_line
			(start 0.67945 0.3048)
			(end 0.120396 0.3048)
			(stroke
				(width 0.1)
				(type default)
			)
			(layer "F.Fab")
		)
		(fp_line
			(start 0.120396 0.3048)
			(end 0.120396 0.2794)
			(stroke
				(width 0.1)
				(type default)
			)
			(layer "F.Fab")
		)
		(fp_line
			(start -0.12065 0.3048)
			(end -0.67945 0.3048)
			(stroke
				(width 0.1)
				(type default)
			)
			(layer "F.Fab")
		)
		(fp_line
			(start -0.67945 0.3048)
			(end -0.67945 -0.305054)
			(stroke
				(width 0.1)
				(type default)
			)
			(layer "F.Fab")
		)
		(pad "1" smd circle
			(at -0.40005 0 90)
			(size 0 0)
			(layers "F.Cu" "F.Mask" "F.Paste")
			(net "PVDDIO_P0_VCC3")
		)
		(pad "2" smd circle
			(at 0.40005 0 90)
			(size 0 0)
			(layers "F.Cu" "F.Mask" "F.Paste")
			(net "GND")
		)
	)
	(footprint ""
		(layer "F.Cu")
		(at 430.02835 -398.91208 180)
		(property "Reference" "R1056"
			(at 0 0 180)
			(layer "F.SilkS")
			(hide yes)
			(effects
				(font
					(size 1.27 1.27)
				)
			)
		)
		(property "Value" ""
			(at 0 0 180)
			(layer "F.Fab")
			(effects
				(font
					(size 1.27 1.27)
				)
			)
		)
		(duplicate_pad_numbers_are_jumpers no)
		(fp_line
			(start 0.32512 0.175006)
			(end -0.32512 0.175006)
			(stroke
				(width 0.1)
				(type default)
			)
			(layer "F.Fab")
		)
		(fp_line
			(start 0.32512 -0.175006)
			(end 0.32512 0.175006)
			(stroke
				(width 0.1)
				(type default)
			)
			(layer "F.Fab")
		)
		(fp_line
			(start -0.32512 0.175006)
			(end -0.32512 -0.175006)
			(stroke
				(width 0.1)
				(type default)
			)
			(layer "F.Fab")
		)
		(fp_line
			(start -0.32512 -0.175006)
			(end 0.32512 -0.175006)
			(stroke
				(width 0.1)
				(type default)
			)
			(layer "F.Fab")
		)
		(pad "1" smd rect
			(at -0.2667 0 180)
			(size 0.3048 0.381)
			(layers "F.Cu" "F.Mask" "F.Paste")
			(net "RT_CPU0_P2_ADDR3")
		)
		(pad "2" smd rect
			(at 0.2667 0)
			(size 0.3048 0.381)
			(layers "F.Cu" "F.Mask" "F.Paste")
			(net "GND")
		)
	)
	(footprint ""
		(layer "F.Cu")
		(at 356.484682 -414.062418)
		(property "Reference" "R4574"
			(at 0 0 0)
			(layer "F.SilkS")
			(hide yes)
			(effects
				(font
					(size 1.27 1.27)
				)
			)
		)
		(property "Value" ""
			(at 0 0 0)
			(layer "F.Fab")
			(effects
				(font
					(size 1.27 1.27)
				)
			)
		)
		(duplicate_pad_numbers_are_jumpers no)
		(fp_line
			(start -0.7874 -0.4064)
			(end 0.7874 -0.4064)
			(stroke
				(width 0.1524)
				(type default)
			)
			(layer "F.SilkS")
		)
		(fp_line
			(start -0.7874 0.4064)
			(end -0.7874 -0.4064)
			(stroke
				(width 0.1524)
				(type default)
			)
			(layer "F.SilkS")
		)
		(fp_line
			(start 0.7874 -0.4064)
			(end 0.7874 0.4064)
			(stroke
				(width 0.1524)
				(type default)
			)
			(layer "F.SilkS")
		)
		(fp_line
			(start 0.7874 0.4064)
			(end -0.7874 0.4064)
			(stroke
				(width 0.1524)
				(type default)
			)
			(layer "F.SilkS")
		)
		(fp_line
			(start -0.67945 -0.305054)
			(end -0.12065 -0.305054)
			(stroke
				(width 0.1)
				(type default)
			)
			(layer "F.Fab")
		)
		(fp_line
			(start -0.67945 0.3048)
			(end -0.67945 -0.305054)
			(stroke
				(width 0.1)
				(type default)
			)
			(layer "F.Fab")
		)
		(fp_line
			(start -0.12065 -0.305054)
			(end -0.12065 -0.2794)
			(stroke
				(width 0.1)
				(type default)
			)
			(layer "F.Fab")
		)
		(fp_line
			(start -0.12065 -0.2794)
			(end 0.12065 -0.2794)
			(stroke
				(width 0.1)
				(type default)
			)
			(layer "F.Fab")
		)
		(fp_line
			(start -0.12065 0.2794)
			(end -0.12065 0.3048)
			(stroke
				(width 0.1)
				(type default)
			)
			(layer "F.Fab")
		)
		(fp_line
			(start -0.12065 0.3048)
			(end -0.67945 0.3048)
			(stroke
				(width 0.1)
				(type default)
			)
			(layer "F.Fab")
		)
		(fp_line
			(start 0.120396 0.2794)
			(end -0.12065 0.2794)
			(stroke
				(width 0.1)
				(type default)
			)
			(layer "F.Fab")
		)
		(fp_line
			(start 0.120396 0.3048)
			(end 0.120396 0.2794)
			(stroke
				(width 0.1)
				(type default)
			)
			(layer "F.Fab")
		)
		(fp_line
			(start 0.12065 -0.3048)
			(end 0.67945 -0.3048)
			(stroke
				(width 0.1)
				(type default)
			)
			(layer "F.Fab")
		)
		(fp_line
			(start 0.12065 -0.2794)
			(end 0.12065 -0.3048)
			(stroke
				(width 0.1)
				(type default)
			)
			(layer "F.Fab")
		)
		(fp_line
			(start 0.67945 -0.3048)
			(end 0.67945 0.3048)
			(stroke
				(width 0.1)
				(type default)
			)
			(layer "F.Fab")
		)
		(fp_line
			(start 0.67945 0.3048)
			(end 0.120396 0.3048)
			(stroke
				(width 0.1)
				(type default)
			)
			(layer "F.Fab")
		)
		(pad "1" smd circle
			(at -0.40005 0)
			(size 0 0)
			(layers "F.Cu" "F.Mask" "F.Paste")
			(net "PRSNT_CABLE_GPU_A1_N")
		)
		(pad "2" smd circle
			(at 0.40005 0)
			(size 0 0)
			(layers "F.Cu" "F.Mask" "F.Paste")
			(net "PRSNT_CABLE_GPU_A1_ISO_N")
		)
	)
)
